(kicad_pcb
	(version 20260206)
	(generator "pcbnew")
	(generator_version "10.0")
	(general
		(thickness 1.6)
		(legacy_teardrops no)
	)
	(paper "A4")
	(title_block
		(title "04192023_DAF0TMB3IC0_F0TG_MB_C_brd_V02_OCP.brd")
		(comment 1 "Grand Teton / footprints 2090-2097 of 8354")
	)
	(layers
		(0 "F.Cu" signal "TOP")
		(4 "In1.Cu" signal "GND")
		(6 "In2.Cu" signal "IN1")
		(8 "In3.Cu" signal "GND1")
		(10 "In4.Cu" signal "IN2")
		(12 "In5.Cu" signal "GND2")
		(14 "In6.Cu" signal "IN3")
		(16 "In7.Cu" signal "GND3")
		(18 "In8.Cu" signal "VCC")
		(20 "In9.Cu" signal "VCC1")
		(22 "In10.Cu" signal "GND4")
		(24 "In11.Cu" signal "IN4")
		(26 "In12.Cu" signal "GND5")
		(28 "In13.Cu" signal "IN5")
		(30 "In14.Cu" signal "GND6")
		(32 "In15.Cu" signal "IN6")
		(34 "In16.Cu" signal "GND7")
		(2 "B.Cu" signal "BOTTOM")
		(9 "F.Adhes" user "F.Adhesive")
		(11 "B.Adhes" user "B.Adhesive")
		(13 "F.Paste" user "Package Geometry/Pastemask Top")
		(15 "B.Paste" user "Package Geometry/Pastemask Bottom")
		(5 "F.SilkS" user "Ref Des/Silkscreen Top")
		(7 "B.SilkS" user "Ref Des/Silkscreen Bottom")
		(1 "F.Mask" user "Board Geometry/Soldermask Top")
		(3 "B.Mask" user "Board Geometry/Soldermask Bottom")
		(17 "Dwgs.User" user "User.Drawings")
		(19 "Cmts.User" user "User.Comments")
		(21 "Eco1.User" user "User.Eco1")
		(23 "Eco2.User" user "User.Eco2")
		(25 "Edge.Cuts" user "Board Geometry/Outline")
		(27 "Margin" user)
		(31 "F.CrtYd" user "Package Geometry/Place Bound Top")
		(29 "B.CrtYd" user "Package Geometry/Place Bound Bottom")
		(35 "F.Fab" user "Ref Des/Assembly Top")
		(33 "B.Fab" user "Ref Des/Assembly Bottom")
	)
	(footprint ""
		(layer "F.Cu")
		(at 150.502366 -57.220358)
		(property "Reference" "R3623"
			(at 0 0 0)
			(layer "F.SilkS")
			(hide yes)
			(effects
				(font
					(size 1.27 1.27)
				)
			)
		)
		(property "Value" ""
			(at 0 0 0)
			(layer "F.Fab")
			(effects
				(font
					(size 1.27 1.27)
				)
			)
		)
		(duplicate_pad_numbers_are_jumpers no)
		(fp_line
			(start -0.7874 -0.4064)
			(end 0.7874 -0.4064)
			(stroke
				(width 0.1524)
				(type default)
			)
			(layer "F.SilkS")
		)
		(fp_line
			(start -0.7874 0.4064)
			(end -0.7874 -0.4064)
			(stroke
				(width 0.1524)
				(type default)
			)
			(layer "F.SilkS")
		)
		(fp_line
			(start 0.7874 -0.4064)
			(end 0.7874 0.4064)
			(stroke
				(width 0.1524)
				(type default)
			)
			(layer "F.SilkS")
		)
		(fp_line
			(start 0.7874 0.4064)
			(end -0.7874 0.4064)
			(stroke
				(width 0.1524)
				(type default)
			)
			(layer "F.SilkS")
		)
		(fp_line
			(start -0.67945 -0.305054)
			(end -0.12065 -0.305054)
			(stroke
				(width 0.1)
				(type default)
			)
			(layer "F.Fab")
		)
		(fp_line
			(start -0.67945 0.3048)
			(end -0.67945 -0.305054)
			(stroke
				(width 0.1)
				(type default)
			)
			(layer "F.Fab")
		)
		(fp_line
			(start -0.12065 -0.305054)
			(end -0.12065 -0.2794)
			(stroke
				(width 0.1)
				(type default)
			)
			(layer "F.Fab")
		)
		(fp_line
			(start -0.12065 -0.2794)
			(end 0.12065 -0.2794)
			(stroke
				(width 0.1)
				(type default)
			)
			(layer "F.Fab")
		)
		(fp_line
			(start -0.12065 0.2794)
			(end -0.12065 0.3048)
			(stroke
				(width 0.1)
				(type default)
			)
			(layer "F.Fab")
		)
		(fp_line
			(start -0.12065 0.3048)
			(end -0.67945 0.3048)
			(stroke
				(width 0.1)
				(type default)
			)
			(layer "F.Fab")
		)
		(fp_line
			(start 0.120396 0.2794)
			(end -0.12065 0.2794)
			(stroke
				(width 0.1)
				(type default)
			)
			(layer "F.Fab")
		)
		(fp_line
			(start 0.120396 0.3048)
			(end 0.120396 0.2794)
			(stroke
				(width 0.1)
				(type default)
			)
			(layer "F.Fab")
		)
		(fp_line
			(start 0.12065 -0.3048)
			(end 0.67945 -0.3048)
			(stroke
				(width 0.1)
				(type default)
			)
			(layer "F.Fab")
		)
		(fp_line
			(start 0.12065 -0.2794)
			(end 0.12065 -0.3048)
			(stroke
				(width 0.1)
				(type default)
			)
			(layer "F.Fab")
		)
		(fp_line
			(start 0.67945 -0.3048)
			(end 0.67945 0.3048)
			(stroke
				(width 0.1)
				(type default)
			)
			(layer "F.Fab")
		)
		(fp_line
			(start 0.67945 0.3048)
			(end 0.120396 0.3048)
			(stroke
				(width 0.1)
				(type default)
			)
			(layer "F.Fab")
		)
		(pad "1" smd circle
			(at -0.40005 0)
			(size 0 0)
			(layers "F.Cu" "F.Mask" "F.Paste")
			(net "P3V3_AUX")
		)
		(pad "2" smd circle
			(at 0.40005 0)
			(size 0 0)
			(layers "F.Cu" "F.Mask" "F.Paste")
			(net "INA230_4_A1")
		)
	)
	(footprint ""
		(layer "F.Cu")
		(at 351.404936 -162.87369 -90)
		(property "Reference" "PR500"
			(at 0 0 270)
			(layer "F.SilkS")
			(hide yes)
			(effects
				(font
					(size 1.27 1.27)
				)
			)
		)
		(property "Value" ""
			(at 0 0 270)
			(layer "F.Fab")
			(effects
				(font
					(size 1.27 1.27)
				)
			)
		)
		(duplicate_pad_numbers_are_jumpers no)
		(fp_line
			(start -0.7874 0.4064)
			(end -0.7874 -0.4064)
			(stroke
				(width 0.1524)
				(type default)
			)
			(layer "F.SilkS")
		)
		(fp_line
			(start 0.7874 0.4064)
			(end -0.7874 0.4064)
			(stroke
				(width 0.1524)
				(type default)
			)
			(layer "F.SilkS")
		)
		(fp_line
			(start -0.7874 -0.4064)
			(end 0.7874 -0.4064)
			(stroke
				(width 0.1524)
				(type default)
			)
			(layer "F.SilkS")
		)
		(fp_line
			(start 0.7874 -0.4064)
			(end 0.7874 0.4064)
			(stroke
				(width 0.1524)
				(type default)
			)
			(layer "F.SilkS")
		)
		(fp_line
			(start -0.67945 0.3048)
			(end -0.67945 -0.305054)
			(stroke
				(width 0.1)
				(type default)
			)
			(layer "F.Fab")
		)
		(fp_line
			(start -0.12065 0.3048)
			(end -0.67945 0.3048)
			(stroke
				(width 0.1)
				(type default)
			)
			(layer "F.Fab")
		)
		(fp_line
			(start 0.120396 0.3048)
			(end 0.120396 0.2794)
			(stroke
				(width 0.1)
				(type default)
			)
			(layer "F.Fab")
		)
		(fp_line
			(start 0.67945 0.3048)
			(end 0.120396 0.3048)
			(stroke
				(width 0.1)
				(type default)
			)
			(layer "F.Fab")
		)
		(fp_line
			(start -0.12065 0.2794)
			(end -0.12065 0.3048)
			(stroke
				(width 0.1)
				(type default)
			)
			(layer "F.Fab")
		)
		(fp_line
			(start 0.120396 0.2794)
			(end -0.12065 0.2794)
			(stroke
				(width 0.1)
				(type default)
			)
			(layer "F.Fab")
		)
		(fp_line
			(start -0.12065 -0.2794)
			(end 0.12065 -0.2794)
			(stroke
				(width 0.1)
				(type default)
			)
			(layer "F.Fab")
		)
		(fp_line
			(start 0.12065 -0.2794)
			(end 0.12065 -0.3048)
			(stroke
				(width 0.1)
				(type default)
			)
			(layer "F.Fab")
		)
		(fp_line
			(start 0.12065 -0.3048)
			(end 0.67945 -0.3048)
			(stroke
				(width 0.1)
				(type default)
			)
			(layer "F.Fab")
		)
		(fp_line
			(start 0.67945 -0.3048)
			(end 0.67945 0.3048)
			(stroke
				(width 0.1)
				(type default)
			)
			(layer "F.Fab")
		)
		(fp_line
			(start -0.67945 -0.305054)
			(end -0.12065 -0.305054)
			(stroke
				(width 0.1)
				(type default)
			)
			(layer "F.Fab")
		)
		(fp_line
			(start -0.12065 -0.305054)
			(end -0.12065 -0.2794)
			(stroke
				(width 0.1)
				(type default)
			)
			(layer "F.Fab")
		)
		(pad "1" smd circle
			(at -0.40005 0 270)
			(size 0 0)
			(layers "F.Cu" "F.Mask" "F.Paste")
			(net "SW_PVDDCR_CPU0_P0_SW6_RC")
		)
		(pad "2" smd circle
			(at 0.40005 0 270)
			(size 0 0)
			(layers "F.Cu" "F.Mask" "F.Paste")
			(net "GND")
		)
	)
	(footprint ""
		(layer "F.Cu")
		(at 310.902096 -383.88163 -90)
		(property "Reference" "C919"
			(at 0 0 270)
			(layer "F.SilkS")
			(hide yes)
			(effects
				(font
					(size 1.27 1.27)
				)
			)
		)
		(property "Value" ""
			(at 0 0 270)
			(layer "F.Fab")
			(effects
				(font
					(size 1.27 1.27)
				)
			)
		)
		(duplicate_pad_numbers_are_jumpers no)
		(fp_line
			(start -0.299974 0.150114)
			(end -0.299974 -0.150114)
			(stroke
				(width 0.1)
				(type default)
			)
			(layer "F.Fab")
		)
		(fp_line
			(start 0.299974 0.150114)
			(end -0.299974 0.150114)
			(stroke
				(width 0.1)
				(type default)
			)
			(layer "F.Fab")
		)
		(fp_line
			(start -0.299974 -0.150114)
			(end 0.299974 -0.150114)
			(stroke
				(width 0.1)
				(type default)
			)
			(layer "F.Fab")
		)
		(fp_line
			(start 0.299974 -0.150114)
			(end 0.299974 0.150114)
			(stroke
				(width 0.1)
				(type default)
			)
			(layer "F.Fab")
		)
		(pad "1" smd rect
			(at -0.2667 0 270)
			(size 0.3048 0.381)
			(layers "F.Cu" "F.Mask" "F.Paste")
			(net "P5E_CPU0_P0_TX_C_DP<7>")
		)
		(pad "2" smd rect
			(at 0.2667 0 270)
			(size 0.3048 0.381)
			(layers "F.Cu" "F.Mask" "F.Paste")
			(net "P5E_CPU0_P0_TX_DP<7>")
		)
	)
	(footprint ""
		(layer "F.Cu")
		(at 360.81589 -390.652)
		(property "Reference" "R1018"
			(at 0 0 0)
			(layer "F.SilkS")
			(hide yes)
			(effects
				(font
					(size 1.27 1.27)
				)
			)
		)
		(property "Value" ""
			(at 0 0 0)
			(layer "F.Fab")
			(effects
				(font
					(size 1.27 1.27)
				)
			)
		)
		(duplicate_pad_numbers_are_jumpers no)
		(fp_line
			(start -0.32512 -0.175006)
			(end 0.32512 -0.175006)
			(stroke
				(width 0.1)
				(type default)
			)
			(layer "F.Fab")
		)
		(fp_line
			(start -0.32512 0.175006)
			(end -0.32512 -0.175006)
			(stroke
				(width 0.1)
				(type default)
			)
			(layer "F.Fab")
		)
		(fp_line
			(start 0.32512 -0.175006)
			(end 0.32512 0.175006)
			(stroke
				(width 0.1)
				(type default)
			)
			(layer "F.Fab")
		)
		(fp_line
			(start 0.32512 0.175006)
			(end -0.32512 0.175006)
			(stroke
				(width 0.1)
				(type default)
			)
			(layer "F.Fab")
		)
		(pad "1" smd rect
			(at -0.2667 0)
			(size 0.3048 0.381)
			(layers "F.Cu" "F.Mask" "F.Paste")
			(net "RT_CPU0_P1_ADDR1")
		)
		(pad "2" smd rect
			(at 0.2667 0 180)
			(size 0.3048 0.381)
			(layers "F.Cu" "F.Mask" "F.Paste")
			(net "GND")
		)
	)
	(footprint ""
		(layer "F.Cu")
		(at 21.938996 -389.171434 -90)
		(property "Reference" "PC6644_09P1_2"
			(at 0 0 270)
			(layer "F.SilkS")
			(hide yes)
			(effects
				(font
					(size 1.27 1.27)
				)
			)
		)
		(property "Value" ""
			(at 0 0 270)
			(layer "F.Fab")
			(effects
				(font
					(size 1.27 1.27)
				)
			)
		)
		(duplicate_pad_numbers_are_jumpers no)
		(fp_line
			(start -0.7874 0.4064)
			(end -0.7874 -0.4064)
			(stroke
				(width 0.1524)
				(type default)
			)
			(layer "F.SilkS")
		)
		(fp_line
			(start 0.7874 0.4064)
			(end -0.7874 0.4064)
			(stroke
				(width 0.1524)
				(type default)
			)
			(layer "F.SilkS")
		)
		(fp_line
			(start -0.7874 -0.4064)
			(end 0.7874 -0.4064)
			(stroke
				(width 0.1524)
				(type default)
			)
			(layer "F.SilkS")
		)
		(fp_line
			(start 0.7874 -0.4064)
			(end 0.7874 0.4064)
			(stroke
				(width 0.1524)
				(type default)
			)
			(layer "F.SilkS")
		)
		(fp_line
			(start -0.67945 0.3048)
			(end -0.67945 -0.305054)
			(stroke
				(width 0.1)
				(type default)
			)
			(layer "F.Fab")
		)
		(fp_line
			(start -0.12065 0.3048)
			(end -0.67945 0.3048)
			(stroke
				(width 0.1)
				(type default)
			)
			(layer "F.Fab")
		)
		(fp_line
			(start 0.120396 0.3048)
			(end 0.120396 0.2794)
			(stroke
				(width 0.1)
				(type default)
			)
			(layer "F.Fab")
		)
		(fp_line
			(start 0.67945 0.3048)
			(end 0.120396 0.3048)
			(stroke
				(width 0.1)
				(type default)
			)
			(layer "F.Fab")
		)
		(fp_line
			(start -0.12065 0.2794)
			(end -0.12065 0.3048)
			(stroke
				(width 0.1)
				(type default)
			)
			(layer "F.Fab")
		)
		(fp_line
			(start 0.120396 0.2794)
			(end -0.12065 0.2794)
			(stroke
				(width 0.1)
				(type default)
			)
			(layer "F.Fab")
		)
		(fp_line
			(start -0.12065 -0.2794)
			(end 0.12065 -0.2794)
			(stroke
				(width 0.1)
				(type default)
			)
			(layer "F.Fab")
		)
		(fp_line
			(start 0.12065 -0.2794)
			(end 0.12065 -0.3048)
			(stroke
				(width 0.1)
				(type default)
			)
			(layer "F.Fab")
		)
		(fp_line
			(start 0.12065 -0.3048)
			(end 0.67945 -0.3048)
			(stroke
				(width 0.1)
				(type default)
			)
			(layer "F.Fab")
		)
		(fp_line
			(start 0.67945 -0.3048)
			(end 0.67945 0.3048)
			(stroke
				(width 0.1)
				(type default)
			)
			(layer "F.Fab")
		)
		(fp_line
			(start -0.67945 -0.305054)
			(end -0.12065 -0.305054)
			(stroke
				(width 0.1)
				(type default)
			)
			(layer "F.Fab")
		)
		(fp_line
			(start -0.12065 -0.305054)
			(end -0.12065 -0.2794)
			(stroke
				(width 0.1)
				(type default)
			)
			(layer "F.Fab")
		)
		(pad "1" smd circle
			(at -0.40005 0 270)
			(size 0 0)
			(layers "F.Cu" "F.Mask" "F.Paste")
			(net "P0V9_RETIMER_CPU1_PVCC")
		)
		(pad "2" smd circle
			(at 0.40005 0 270)
			(size 0 0)
			(layers "F.Cu" "F.Mask" "F.Paste")
			(net "GND")
		)
	)
	(footprint ""
		(layer "F.Cu")
		(at 432.783488 -332.63586 -90)
		(property "Reference" "PC229"
			(at -4.97332 -7.844536 90)
			(unlocked yes)
			(layer "F.SilkS")
			(effects
				(font
					(size 0.7874 0.5842)
					(thickness 0.1524)
				)
				(justify left)
			)
		)
		(property "Value" ""
			(at 0 0 270)
			(layer "F.Fab")
			(effects
				(font
					(size 1.27 1.27)
				)
			)
		)
		(duplicate_pad_numbers_are_jumpers no)
		(fp_line
			(start -1.988058 2.750058)
			(end 2.750058 2.750058)
			(stroke
				(width 0.1524)
				(type default)
			)
			(layer "F.SilkS")
		)
		(fp_line
			(start 2.750058 2.750058)
			(end 2.750058 0.9398)
			(stroke
				(width 0.1524)
				(type default)
			)
			(layer "F.SilkS")
		)
		(fp_line
			(start -2.750058 1.988058)
			(end -1.988058 2.750058)
			(stroke
				(width 0.1524)
				(type default)
			)
			(layer "F.SilkS")
		)
		(fp_line
			(start -2.750058 0.9398)
			(end -2.750058 1.988058)
			(stroke
				(width 0.1524)
				(type default)
			)
			(layer "F.SilkS")
		)
		(fp_line
			(start 2.750058 -0.9398)
			(end 2.750058 -2.750058)
			(stroke
				(width 0.1524)
				(type default)
			)
			(layer "F.SilkS")
		)
		(fp_line
			(start -2.750058 -1.988058)
			(end -2.750058 -0.9398)
			(stroke
				(width 0.1524)
				(type default)
			)
			(layer "F.SilkS")
		)
		(fp_line
			(start -1.988058 -2.750058)
			(end -2.750058 -1.988058)
			(stroke
				(width 0.1524)
				(type default)
			)
			(layer "F.SilkS")
		)
		(fp_line
			(start 2.750058 -2.750058)
			(end -1.988058 -2.750058)
			(stroke
				(width 0.1524)
				(type default)
			)
			(layer "F.SilkS")
		)
		(fp_line
			(start -2.750058 2.750058)
			(end 2.750058 2.750058)
			(stroke
				(width 0.1)
				(type default)
			)
			(layer "F.Fab")
		)
		(fp_line
			(start 2.750058 2.750058)
			(end 2.750058 -2.750058)
			(stroke
				(width 0.1)
				(type default)
			)
			(layer "F.Fab")
		)
		(fp_line
			(start -2.750058 -2.750058)
			(end -2.750058 2.750058)
			(stroke
				(width 0.1)
				(type default)
			)
			(layer "F.Fab")
		)
		(fp_line
			(start 2.750058 -2.750058)
			(end -2.750058 -2.750058)
			(stroke
				(width 0.1)
				(type default)
			)
			(layer "F.Fab")
		)
		(pad "1" smd rect
			(at -2.199894 0)
			(size 1.6002 3.0226)
			(layers "F.Cu" "F.Mask" "F.Paste")
			(net "PVDD11_S3_P0")
		)
		(pad "2" smd rect
			(at 2.199894 0)
			(size 1.6002 3.0226)
			(layers "F.Cu" "F.Mask" "F.Paste")
			(net "GND")
		)
	)
	(footprint ""
		(layer "F.Cu")
		(at 300.022514 -24.349456)
		(property "Reference" "R1777"
			(at 0 0 0)
			(layer "F.SilkS")
			(hide yes)
			(effects
				(font
					(size 1.27 1.27)
				)
			)
		)
		(property "Value" ""
			(at 0 0 0)
			(layer "F.Fab")
			(effects
				(font
					(size 1.27 1.27)
				)
			)
		)
		(duplicate_pad_numbers_are_jumpers no)
		(fp_line
			(start -0.7874 -0.4064)
			(end 0.7874 -0.4064)
			(stroke
				(width 0.1524)
				(type default)
			)
			(layer "F.SilkS")
		)
		(fp_line
			(start -0.7874 0.4064)
			(end -0.7874 -0.4064)
			(stroke
				(width 0.1524)
				(type default)
			)
			(layer "F.SilkS")
		)
		(fp_line
			(start 0.7874 -0.4064)
			(end 0.7874 0.4064)
			(stroke
				(width 0.1524)
				(type default)
			)
			(layer "F.SilkS")
		)
		(fp_line
			(start 0.7874 0.4064)
			(end -0.7874 0.4064)
			(stroke
				(width 0.1524)
				(type default)
			)
			(layer "F.SilkS")
		)
		(fp_line
			(start -0.67945 -0.305054)
			(end -0.12065 -0.305054)
			(stroke
				(width 0.1)
				(type default)
			)
			(layer "F.Fab")
		)
		(fp_line
			(start -0.67945 0.3048)
			(end -0.67945 -0.305054)
			(stroke
				(width 0.1)
				(type default)
			)
			(layer "F.Fab")
		)
		(fp_line
			(start -0.12065 -0.305054)
			(end -0.12065 -0.2794)
			(stroke
				(width 0.1)
				(type default)
			)
			(layer "F.Fab")
		)
		(fp_line
			(start -0.12065 -0.2794)
			(end 0.12065 -0.2794)
			(stroke
				(width 0.1)
				(type default)
			)
			(layer "F.Fab")
		)
		(fp_line
			(start -0.12065 0.2794)
			(end -0.12065 0.3048)
			(stroke
				(width 0.1)
				(type default)
			)
			(layer "F.Fab")
		)
		(fp_line
			(start -0.12065 0.3048)
			(end -0.67945 0.3048)
			(stroke
				(width 0.1)
				(type default)
			)
			(layer "F.Fab")
		)
		(fp_line
			(start 0.120396 0.2794)
			(end -0.12065 0.2794)
			(stroke
				(width 0.1)
				(type default)
			)
			(layer "F.Fab")
		)
		(fp_line
			(start 0.120396 0.3048)
			(end 0.120396 0.2794)
			(stroke
				(width 0.1)
				(type default)
			)
			(layer "F.Fab")
		)
		(fp_line
			(start 0.12065 -0.3048)
			(end 0.67945 -0.3048)
			(stroke
				(width 0.1)
				(type default)
			)
			(layer "F.Fab")
		)
		(fp_line
			(start 0.12065 -0.2794)
			(end 0.12065 -0.3048)
			(stroke
				(width 0.1)
				(type default)
			)
			(layer "F.Fab")
		)
		(fp_line
			(start 0.67945 -0.3048)
			(end 0.67945 0.3048)
			(stroke
				(width 0.1)
				(type default)
			)
			(layer "F.Fab")
		)
		(fp_line
			(start 0.67945 0.3048)
			(end 0.120396 0.3048)
			(stroke
				(width 0.1)
				(type default)
			)
			(layer "F.Fab")
		)
		(pad "1" smd circle
			(at -0.40005 0)
			(size 0 0)
			(layers "F.Cu" "F.Mask" "F.Paste")
			(net "P1V5_BAT_IN")
		)
		(pad "2" smd circle
			(at 0.40005 0)
			(size 0 0)
			(layers "F.Cu" "F.Mask" "F.Paste")
			(net "BAT_LDO_EN")
		)
	)
	(footprint ""
		(layer "F.Cu")
		(at 392.840972 -385.364228)
		(property "Reference" "C873"
			(at 0 0 0)
			(layer "F.SilkS")
			(hide yes)
			(effects
				(font
					(size 1.27 1.27)
				)
			)
		)
		(property "Value" ""
			(at 0 0 0)
			(layer "F.Fab")
			(effects
				(font
					(size 1.27 1.27)
				)
			)
		)
		(duplicate_pad_numbers_are_jumpers no)
		(fp_line
			(start -0.299974 -0.150114)
			(end 0.299974 -0.150114)
			(stroke
				(width 0.1)
				(type default)
			)
			(layer "F.Fab")
		)
		(fp_line
			(start -0.299974 0.150114)
			(end -0.299974 -0.150114)
			(stroke
				(width 0.1)
				(type default)
			)
			(layer "F.Fab")
		)
		(fp_line
			(start 0.299974 -0.150114)
			(end 0.299974 0.150114)
			(stroke
				(width 0.1)
				(type default)
			)
			(layer "F.Fab")
		)
		(fp_line
			(start 0.299974 0.150114)
			(end -0.299974 0.150114)
			(stroke
				(width 0.1)
				(type default)
			)
			(layer "F.Fab")
		)
		(pad "1" smd rect
			(at -0.2667 0)
			(size 0.3048 0.381)
			(layers "F.Cu" "F.Mask" "F.Paste")
			(net "P5E_CPU0_P3_TX_C_DP<14>")
		)
		(pad "2" smd rect
			(at 0.2667 0)
			(size 0.3048 0.381)
			(layers "F.Cu" "F.Mask" "F.Paste")
			(net "P5E_CPU0_P3_TX_DP<14>")
		)
	)
)
